# T6G (Grand Teton) — schematic netlist excerpt (pin names and nets, part order shuffled) for the footprints in the layout excerpt that follows; sources: Cadence DE-HDL packaged netlist, KiCad conversion of 04192023_DAF0TMB3IC0_F0TG_MB_C_brd_V02_OCP.brd

R887  Q_RES  1K 1% EMPTY  pkg 0201LF  page 342 : A = P1V8_CPU1_RT_1D ; B = RT_CPU1_P2_ADDR1
C1103  Q_CAP  0.1UF 25V 10% X7R  pkg 0402  page 77 : A = PVDD18_S5_P0 ; B = GND
R86  Q_RES  0 5% CHIP  pkg 0402LF  page 238 : A = SMB_FRU_3V3AUX_SDA ; B = SMB_FRU_3V3AUX_R1_SDA

(kicad_pcb
	(version 20260206)
	(generator "pcbnew")
	(generator_version "10.0")
	(general
		(thickness 1.6)
		(legacy_teardrops no)
	)
	(paper "A4")
	(title_block
		(title "04192023_DAF0TMB3IC0_F0TG_MB_C_brd_V02_OCP.brd")
		(comment 1 "Grand Teton / footprints 1113-1115 of 8354")
	)
	(layers
		(0 "F.Cu" signal "TOP")
		(4 "In1.Cu" signal "GND")
		(6 "In2.Cu" signal "IN1")
		(8 "In3.Cu" signal "GND1")
		(10 "In4.Cu" signal "IN2")
		(12 "In5.Cu" signal "GND2")
		(14 "In6.Cu" signal "IN3")
		(16 "In7.Cu" signal "GND3")
		(18 "In8.Cu" signal "VCC")
		(20 "In9.Cu" signal "VCC1")
		(22 "In10.Cu" signal "GND4")
		(24 "In11.Cu" signal "IN4")
		(26 "In12.Cu" signal "GND5")
		(28 "In13.Cu" signal "IN5")
		(30 "In14.Cu" signal "GND6")
		(32 "In15.Cu" signal "IN6")
		(34 "In16.Cu" signal "GND7")
		(2 "B.Cu" signal "BOTTOM")
		(9 "F.Adhes" user "F.Adhesive")
		(11 "B.Adhes" user "B.Adhesive")
		(13 "F.Paste" user "Package Geometry/Pastemask Top")
		(15 "B.Paste" user "Package Geometry/Pastemask Bottom")
		(5 "F.SilkS" user "Ref Des/Silkscreen Top")
		(7 "B.SilkS" user "Ref Des/Silkscreen Bottom")
		(1 "F.Mask" user "Board Geometry/Soldermask Top")
		(3 "B.Mask" user "Board Geometry/Soldermask Bottom")
		(17 "Dwgs.User" user "User.Drawings")
		(19 "Cmts.User" user "User.Comments")
		(21 "Eco1.User" user "User.Eco1")
		(23 "Eco2.User" user "User.Eco2")
		(25 "Edge.Cuts" user "Board Geometry/Outline")
		(27 "Margin" user)
		(31 "F.CrtYd" user "Package Geometry/Place Bound Top")
		(29 "B.CrtYd" user "Package Geometry/Place Bound Bottom")
		(35 "F.Fab" user "Ref Des/Assembly Top")
		(33 "B.Fab" user "Ref Des/Assembly Bottom")
	)
	(footprint ""
		(layer "F.Cu")
		(at 262.848852 -137.103104 -90)
		(property "Reference" "C1103"
			(at 0 0 270)
			(layer "F.SilkS")
			(hide yes)
			(effects
				(font
					(size 1.27 1.27)
				)
			)
		)
		(property "Value" ""
			(at 0 0 270)
			(layer "F.Fab")
			(effects
				(font
					(size 1.27 1.27)
				)
			)
		)
		(duplicate_pad_numbers_are_jumpers no)
		(fp_line
			(start -0.7874 0.4064)
			(end -0.7874 -0.4064)
			(stroke
				(width 0.1524)
				(type default)
			)
			(layer "F.SilkS")
		)
		(fp_line
			(start 0.7874 0.4064)
			(end -0.7874 0.4064)
			(stroke
				(width 0.1524)
				(type default)
			)
			(layer "F.SilkS")
		)
		(fp_line
			(start -0.7874 -0.4064)
			(end 0.7874 -0.4064)
			(stroke
				(width 0.1524)
				(type default)
			)
			(layer "F.SilkS")
		)
		(fp_line
			(start 0.7874 -0.4064)
			(end 0.7874 0.4064)
			(stroke
				(width 0.1524)
				(type default)
			)
			(layer "F.SilkS")
		)
		(fp_line
			(start -0.67945 0.3048)
			(end -0.67945 -0.305054)
			(stroke
				(width 0.1)
				(type default)
			)
			(layer "F.Fab")
		)
		(fp_line
			(start -0.12065 0.3048)
			(end -0.67945 0.3048)
			(stroke
				(width 0.1)
				(type default)
			)
			(layer "F.Fab")
		)
		(fp_line
			(start 0.120396 0.3048)
			(end 0.120396 0.2794)
			(stroke
				(width 0.1)
				(type default)
			)
			(layer "F.Fab")
		)
		(fp_line
			(start 0.67945 0.3048)
			(end 0.120396 0.3048)
			(stroke
				(width 0.1)
				(type default)
			)
			(layer "F.Fab")
		)
		(fp_line
			(start -0.12065 0.2794)
			(end -0.12065 0.3048)
			(stroke
				(width 0.1)
				(type default)
			)
			(layer "F.Fab")
		)
		(fp_line
			(start 0.120396 0.2794)
			(end -0.12065 0.2794)
			(stroke
				(width 0.1)
				(type default)
			)
			(layer "F.Fab")
		)
		(fp_line
			(start -0.12065 -0.2794)
			(end 0.12065 -0.2794)
			(stroke
				(width 0.1)
				(type default)
			)
			(layer "F.Fab")
		)
		(fp_line
			(start 0.12065 -0.2794)
			(end 0.12065 -0.3048)
			(stroke
				(width 0.1)
				(type default)
			)
			(layer "F.Fab")
		)
		(fp_line
			(start 0.12065 -0.3048)
			(end 0.67945 -0.3048)
			(stroke
				(width 0.1)
				(type default)
			)
			(layer "F.Fab")
		)
		(fp_line
			(start 0.67945 -0.3048)
			(end 0.67945 0.3048)
			(stroke
				(width 0.1)
				(type default)
			)
			(layer "F.Fab")
		)
		(fp_line
			(start -0.67945 -0.305054)
			(end -0.12065 -0.305054)
			(stroke
				(width 0.1)
				(type default)
			)
			(layer "F.Fab")
		)
		(fp_line
			(start -0.12065 -0.305054)
			(end -0.12065 -0.2794)
			(stroke
				(width 0.1)
				(type default)
			)
			(layer "F.Fab")
		)
		(pad "1" smd circle
			(at -0.40005 0 270)
			(size 0 0)
			(layers "F.Cu" "F.Mask" "F.Paste")
			(net "PVDD18_S5_P0")
		)
		(pad "2" smd circle
			(at 0.40005 0 270)
			(size 0 0)
			(layers "F.Cu" "F.Mask" "F.Paste")
			(net "GND")
		)
	)
	(footprint ""
		(layer "F.Cu")
		(at 170.979846 -383.11709 180)
		(property "Reference" "R887"
			(at 0 0 180)
			(layer "F.SilkS")
			(hide yes)
			(effects
				(font
					(size 1.27 1.27)
				)
			)
		)
		(property "Value" ""
			(at 0 0 180)
			(layer "F.Fab")
			(effects
				(font
					(size 1.27 1.27)
				)
			)
		)
		(duplicate_pad_numbers_are_jumpers no)
		(fp_line
			(start 0.32512 0.175006)
			(end -0.32512 0.175006)
			(stroke
				(width 0.1)
				(type default)
			)
			(layer "F.Fab")
		)
		(fp_line
			(start 0.32512 -0.175006)
			(end 0.32512 0.175006)
			(stroke
				(width 0.1)
				(type default)
			)
			(layer "F.Fab")
		)
		(fp_line
			(start -0.32512 0.175006)
			(end -0.32512 -0.175006)
			(stroke
				(width 0.1)
				(type default)
			)
			(layer "F.Fab")
		)
		(fp_line
			(start -0.32512 -0.175006)
			(end 0.32512 -0.175006)
			(stroke
				(width 0.1)
				(type default)
			)
			(layer "F.Fab")
		)
		(pad "1" smd rect
			(at -0.2667 0 180)
			(size 0.3048 0.381)
			(layers "F.Cu" "F.Mask" "F.Paste")
			(net "P1V8_CPU1_RT_1D")
		)
		(pad "2" smd rect
			(at 0.2667 0)
			(size 0.3048 0.381)
			(layers "F.Cu" "F.Mask" "F.Paste")
			(net "RT_CPU1_P2_ADDR1")
		)
	)
	(footprint ""
		(layer "F.Cu")
		(at 317.896748 -115.108228 180)
		(property "Reference" "R86"
			(at 0 0 180)
			(layer "F.SilkS")
			(hide yes)
			(effects
				(font
					(size 1.27 1.27)
				)
			)
		)
		(property "Value" ""
			(at 0 0 180)
			(layer "F.Fab")
			(effects
				(font
					(size 1.27 1.27)
				)
			)
		)
		(duplicate_pad_numbers_are_jumpers no)
		(fp_line
			(start 0.7874 0.4064)
			(end -0.7874 0.4064)
			(stroke
				(width 0.1524)
				(type default)
			)
			(layer "F.SilkS")
		)
		(fp_line
			(start 0.7874 -0.4064)
			(end 0.7874 0.4064)
			(stroke
				(width 0.1524)
				(type default)
			)
			(layer "F.SilkS")
		)
		(fp_line
			(start -0.7874 0.4064)
			(end -0.7874 -0.4064)
			(stroke
				(width 0.1524)
				(type default)
			)
			(layer "F.SilkS")
		)
		(fp_line
			(start -0.7874 -0.4064)
			(end 0.7874 -0.4064)
			(stroke
				(width 0.1524)
				(type default)
			)
			(layer "F.SilkS")
		)
		(fp_line
			(start 0.67945 0.3048)
			(end 0.120396 0.3048)
			(stroke
				(width 0.1)
				(type default)
			)
			(layer "F.Fab")
		)
		(fp_line
			(start 0.67945 -0.3048)
			(end 0.67945 0.3048)
			(stroke
				(width 0.1)
				(type default)
			)
			(layer "F.Fab")
		)
		(fp_line
			(start 0.12065 -0.2794)
			(end 0.12065 -0.3048)
			(stroke
				(width 0.1)
				(type default)
			)
			(layer "F.Fab")
		)
		(fp_line
			(start 0.12065 -0.3048)
			(end 0.67945 -0.3048)
			(stroke
				(width 0.1)
				(type default)
			)
			(layer "F.Fab")
		)
		(fp_line
			(start 0.120396 0.3048)
			(end 0.120396 0.2794)
			(stroke
				(width 0.1)
				(type default)
			)
			(layer "F.Fab")
		)
		(fp_line
			(start 0.120396 0.2794)
			(end -0.12065 0.2794)
			(stroke
				(width 0.1)
				(type default)
			)
			(layer "F.Fab")
		)
		(fp_line
			(start -0.12065 0.3048)
			(end -0.67945 0.3048)
			(stroke
				(width 0.1)
				(type default)
			)
			(layer "F.Fab")
		)
		(fp_line
			(start -0.12065 0.2794)
			(end -0.12065 0.3048)
			(stroke
				(width 0.1)
				(type default)
			)
			(layer "F.Fab")
		)
		(fp_line
			(start -0.12065 -0.2794)
			(end 0.12065 -0.2794)
			(stroke
				(width 0.1)
				(type default)
			)
			(layer "F.Fab")
		)
		(fp_line
			(start -0.12065 -0.305054)
			(end -0.12065 -0.2794)
			(stroke
				(width 0.1)
				(type default)
			)
			(layer "F.Fab")
		)
		(fp_line
			(start -0.67945 0.3048)
			(end -0.67945 -0.305054)
			(stroke
				(width 0.1)
				(type default)
			)
			(layer "F.Fab")
		)
		(fp_line
			(start -0.67945 -0.305054)
			(end -0.12065 -0.305054)
			(stroke
				(width 0.1)
				(type default)
			)
			(layer "F.Fab")
		)
		(pad "1" smd circle
			(at -0.40005 0 180)
			(size 0 0)
			(layers "F.Cu" "F.Mask" "F.Paste")
			(net "SMB_FRU_3V3AUX_SDA")
		)
		(pad "2" smd circle
			(at 0.40005 0 180)
			(size 0 0)
			(layers "F.Cu" "F.Mask" "F.Paste")
			(net "SMB_FRU_3V3AUX_R1_SDA")
		)
	)
)
